(kicad_pcb
	(version 20221018)
	(generator pcbnew)
	(general
    (thickness 0.908)
  )
	(paper "A4")
	(title_block
    (title "HDMI-MIPI Bridge")
    (date "2024-04-24")
    (rev "1.3.2")
		(comment 9 "footprints 113-115 of 121")
	)
	(layers
    (0 "F.Cu" signal)
    (1 "In1.Cu" signal)
    (2 "In2.Cu" signal)
    (31 "B.Cu" signal)
    (32 "B.Adhes" user "B.Adhesive")
    (33 "F.Adhes" user "F.Adhesive")
    (34 "B.Paste" user)
    (35 "F.Paste" user)
    (36 "B.SilkS" user "B.Silkscreen")
    (37 "F.SilkS" user "F.Silkscreen")
    (38 "B.Mask" user)
    (39 "F.Mask" user)
    (40 "Dwgs.User" user "User.Drawings")
    (41 "Cmts.User" user "User.Comments")
    (42 "Eco1.User" user "User.Eco1")
    (43 "Eco2.User" user "User.Eco2")
    (44 "Edge.Cuts" user)
    (45 "Margin" user)
    (46 "B.CrtYd" user "B.Courtyard")
    (47 "F.CrtYd" user "F.Courtyard")
    (48 "B.Fab" user)
    (49 "F.Fab" user)
  )
	(footprint "antmicro-footprints:Spacer_Drill3.7mm_H6mm_9774060151R" (layer "B.Cu")
    (at 119 94 180)
    (property "Author" "Antmicro")
    (property "License" "Apache-2.0")
    (property "MPN" "9774060151R")
    (property "Manufacturer" "Würth Elektronik")
    (property "Public" "False")
    (property "Sheetfile" "csi.kicad_sch")
    (property "Sheetname" "CSI")
    (property "ki_description" "Spacer, SMT, Non Stop, Steel, Swage Round, 5.1 mm x 6 mm, M2.5 Thread, WA-SMSI Series")
    (property "ki_keywords" "MECHANICAL, SPACER")
    (attr smd)
    (fp_text reference "SP1" (at 0 3.2) (layer "B.SilkS") hide
        (effects (font (size 0.7 0.7) (thickness 0.15)) (justify left bottom mirror))
    )
    (fp_text value "Spacer_Drill3.7mm_H6mm_9774060151R" (at 0 -4) (layer "B.Fab")
        (effects (font (size 0.7 0.7) (thickness 0.15)) (justify left bottom mirror))
    )
    (fp_text user "${REFERENCE}" (at -2.551 -5.25) (layer "B.Fab") hide
        (effects (font (size 0.7 0.7) (thickness 0.15)) (justify left bottom mirror))
    )
    (fp_text user "Author: Antmicro" (at -2.551 -6.5) (layer "B.Fab") hide
        (effects (font (size 0.7 0.7) (thickness 0.15)) (justify left bottom mirror))
    )
    (fp_text user "License: Apache-2.0" (at -2.551 -7.75) (layer "B.Fab") hide
        (effects (font (size 0.7 0.7) (thickness 0.15)) (justify left bottom mirror))
    )
    (fp_circle (center 0 0) (end 3.05 0)
      (stroke (width 0.05) (type solid)) (fill none) (layer "B.CrtYd"))
    (fp_circle (center -0.001 0) (end 2.548 0)
      (stroke (width 0.15) (type solid)) (fill none) (layer "B.Fab"))
    (pad "" smd custom (at -1.71 -1.699 90) (size 0.62 0.62) (layers "B.Paste")
      (thermal_bridge_angle 90)
      (options (clearance outline) (anchor circle))
      (primitives
        (gr_arc (start 1.266786 0.24747) (mid 0.285453 -0.29439) (end -0.250195 -1.279127) (width 0.2))
        (gr_arc (start 1.259603 0.339191) (mid 0.218448 -0.232561) (end -0.34334 -1.279127) (width 0.2))
        (gr_arc (start 1.255279 0.431435) (mid 0.152481 -0.169693) (end -0.436309 -1.279127) (width 0.2))
        (gr_arc (start 1.253811 0.524161) (mid 0.087542 -0.105784) (end -0.529126 -1.279127) (width 0.2))
        (gr_arc (start 1.275473 0.621136) (mid 0.0309 -0.033527) (end -0.621807 -1.279127) (width 0.2))
        (gr_arc (start 1.263664 0.711602) (mid -0.037759 0.026651) (end -0.71437 -1.279127) (width 0.2))
        (gr_arc (start 1.253435 0.802342) (mid -0.105837 0.087395) (end -0.806826 -1.279127) (width 0.2))
        (gr_arc (start 1.267475 0.897258) (mid -0.165236 0.156885) (end -0.899187 -1.279127) (width 0.2))
        (gr_arc (start 1.270645 0.990112) (mid -0.228522 0.222449) (end -0.991463 -1.279127) (width 0.2))
        (gr_arc (start 1.266278 1.081674) (mid -0.294507 0.285313) (end -1.083663 -1.279127) (width 0.2))
        (gr_line (start 1.279127 1.083663) (end 1.279127 0.250195) (width 0.2))
        (gr_line (start -1.083663 -1.279127) (end -0.250195 -1.279127) (width 0.2))
      ))
    (pad "" smd custom (at -1.71 1.71 180) (size 0.62 0.62) (layers "B.Paste")
      (thermal_bridge_angle 90)
      (options (clearance outline) (anchor circle))
      (primitives
        (gr_arc (start 1.266786 0.24747) (mid 0.285453 -0.29439) (end -0.250195 -1.279127) (width 0.2))
        (gr_arc (start 1.259603 0.339191) (mid 0.218448 -0.232561) (end -0.34334 -1.279127) (width 0.2))
        (gr_arc (start 1.255279 0.431435) (mid 0.152481 -0.169693) (end -0.436309 -1.279127) (width 0.2))
        (gr_arc (start 1.253811 0.524161) (mid 0.087542 -0.105784) (end -0.529126 -1.279127) (width 0.2))
        (gr_arc (start 1.275473 0.621136) (mid 0.0309 -0.033527) (end -0.621807 -1.279127) (width 0.2))
        (gr_arc (start 1.263664 0.711602) (mid -0.037759 0.026651) (end -0.71437 -1.279127) (width 0.2))
        (gr_arc (start 1.253435 0.802342) (mid -0.105837 0.087395) (end -0.806826 -1.279127) (width 0.2))
        (gr_arc (start 1.267475 0.897258) (mid -0.165236 0.156885) (end -0.899187 -1.279127) (width 0.2))
        (gr_arc (start 1.270645 0.990112) (mid -0.228522 0.222449) (end -0.991463 -1.279127) (width 0.2))
        (gr_arc (start 1.266278 1.081674) (mid -0.294507 0.285313) (end -1.083663 -1.279127) (width 0.2))
        (gr_line (start 1.279127 1.083663) (end 1.279127 0.250195) (width 0.2))
        (gr_line (start -1.083663 -1.279127) (end -0.250195 -1.279127) (width 0.2))
      ))
    (pad "" smd custom (at 1.699 -1.699) (size 0.62 0.62) (layers "B.Paste")
      (thermal_bridge_angle 90)
      (options (clearance outline) (anchor circle))
      (primitives
        (gr_arc (start 1.266786 0.24747) (mid 0.285453 -0.29439) (end -0.250195 -1.279127) (width 0.2))
        (gr_arc (start 1.259603 0.339191) (mid 0.218448 -0.232561) (end -0.34334 -1.279127) (width 0.2))
        (gr_arc (start 1.255279 0.431435) (mid 0.152481 -0.169693) (end -0.436309 -1.279127) (width 0.2))
        (gr_arc (start 1.253811 0.524161) (mid 0.087542 -0.105784) (end -0.529126 -1.279127) (width 0.2))
        (gr_arc (start 1.275473 0.621136) (mid 0.0309 -0.033527) (end -0.621807 -1.279127) (width 0.2))
        (gr_arc (start 1.263664 0.711602) (mid -0.037759 0.026651) (end -0.71437 -1.279127) (width 0.2))
        (gr_arc (start 1.253435 0.802342) (mid -0.105837 0.087395) (end -0.806826 -1.279127) (width 0.2))
        (gr_arc (start 1.267475 0.897258) (mid -0.165236 0.156885) (end -0.899187 -1.279127) (width 0.2))
        (gr_arc (start 1.270645 0.990112) (mid -0.228522 0.222449) (end -0.991463 -1.279127) (width 0.2))
        (gr_arc (start 1.266278 1.081674) (mid -0.294507 0.285313) (end -1.083663 -1.279127) (width 0.2))
        (gr_line (start 1.279127 1.083663) (end 1.279127 0.250195) (width 0.2))
        (gr_line (start -1.083663 -1.279127) (end -0.250195 -1.279127) (width 0.2))
      ))
    (pad "" smd custom (at 1.699 1.71 270) (size 0.62 0.62) (layers "B.Paste")
      (thermal_bridge_angle 90)
      (options (clearance outline) (anchor circle))
      (primitives
        (gr_arc (start 1.266786 0.24747) (mid 0.285453 -0.29439) (end -0.250195 -1.279127) (width 0.2))
        (gr_arc (start 1.259603 0.339191) (mid 0.218448 -0.232561) (end -0.34334 -1.279127) (width 0.2))
        (gr_arc (start 1.255279 0.431435) (mid 0.152481 -0.169693) (end -0.436309 -1.279127) (width 0.2))
        (gr_arc (start 1.253811 0.524161) (mid 0.087542 -0.105784) (end -0.529126 -1.279127) (width 0.2))
        (gr_arc (start 1.275473 0.621136) (mid 0.0309 -0.033527) (end -0.621807 -1.279127) (width 0.2))
        (gr_arc (start 1.263664 0.711602) (mid -0.037759 0.026651) (end -0.71437 -1.279127) (width 0.2))
        (gr_arc (start 1.253435 0.802342) (mid -0.105837 0.087395) (end -0.806826 -1.279127) (width 0.2))
        (gr_arc (start 1.267475 0.897258) (mid -0.165236 0.156885) (end -0.899187 -1.279127) (width 0.2))
        (gr_arc (start 1.270645 0.990112) (mid -0.228522 0.222449) (end -0.991463 -1.279127) (width 0.2))
        (gr_arc (start 1.266278 1.081674) (mid -0.294507 0.285313) (end -1.083663 -1.279127) (width 0.2))
        (gr_line (start 1.279127 1.083663) (end 1.279127 0.250195) (width 0.2))
        (gr_line (start -1.083663 -1.279127) (end -0.250195 -1.279127) (width 0.2))
      ))
    (pad "1" thru_hole circle (at -0.001 0 180) (size 6 6) (drill 3.7) (layers "*.Cu" "*.Mask")
      (net 2 "GND") (pintype "passive") (solder_paste_margin_ratio -0.05))
  )
	(footprint "antmicro-footprints:R_0603_1608Metric" (layer "B.Cu")
    (at 130.8 110.9 180)
    (descr "Resistor SMD 0603")
    (tags "resistor SMD 0603")
    (property "Author" "Antmicro")
    (property "Current" "1A")
    (property "License" "Apache-2.0")
    (property "MPN" "CR0603-J/-000ELF")
    (property "Manufacturer" "Bourns")
    (property "Public" "False")
    (property "Sheetfile" "channel1.kicad_sch")
    (property "Sheetname" "Channel 1")
    (property "Tolerance" "")
    (property "Val" "0R")
    (property "ki_description" "Zero Ohm Resistor, Jumper, 0603 [1608 Metric], Thick Film, 100 mW, 1 A, Surface Mount Device, CR")
    (property "ki_keywords" "0603, SMT, RESISTOR, PASSIVE")
    (attr smd)
    (fp_text reference "R6" (at 1 -0.4) (layer "B.SilkS")
        (effects (font (size 0.7 0.7) (thickness 0.15)) (justify left bottom mirror))
    )
    (fp_text value "R_0R_0603" (at 0 -1.6) (layer "B.Fab")
        (effects (font (size 0.7 0.7) (thickness 0.15)) (justify left bottom mirror))
    )
    (fp_text user "${REFERENCE}" (at -1.25 -3.898) (layer "B.Fab") hide
        (effects (font (size 0.7 0.7) (thickness 0.15)) (justify left bottom mirror))
    )
    (fp_text user "License: Apache-2.0" (at -1.25 -5.9) (layer "B.Fab") hide
        (effects (font (size 0.7 0.7) (thickness 0.15)) (justify left bottom mirror))
    )
    (fp_text user "Author: Antmicro" (at -1.25 -4.9) (layer "B.Fab") hide
        (effects (font (size 0.7 0.7) (thickness 0.15)) (justify left bottom mirror))
    )
    (fp_line (start -0.15 -0.4) (end 0.15 -0.4)
      (stroke (width 0.15) (type solid)) (layer "B.SilkS"))
    (fp_line (start -0.15 0.4) (end 0.15 0.4)
      (stroke (width 0.15) (type solid)) (layer "B.SilkS"))
    (fp_rect (start -1.25 0.65) (end 1.25 -0.65)
      (stroke (width 0.05) (type solid)) (fill none) (layer "B.CrtYd"))
    (fp_rect (start -0.8 0.4) (end 0.8 -0.4)
      (stroke (width 0.15) (type solid)) (fill none) (layer "B.Fab"))
    (pad "1" smd roundrect (at -0.7 0 180) (size 0.8 1) (layers "B.Cu" "B.Paste" "B.Mask") (roundrect_rratio 0.2)
      (net 20 "Net-(U1B-VDDIO1)") (pintype "passive"))
    (pad "2" smd roundrect (at 0.7 0 180) (size 0.8 1) (layers "B.Cu" "B.Paste" "B.Mask") (roundrect_rratio 0.2)
      (net 9 "+3V3") (pintype "passive"))
  )
	(footprint "antmicro-footprints:Spacer_Drill3.7mm_H6mm_9774060151R" (layer "B.Cu")
    (at 179 94 180)
    (property "Author" "Antmicro")
    (property "License" "Apache-2.0")
    (property "MPN" "9774060151R")
    (property "Manufacturer" "Würth Elektronik")
    (property "Public" "False")
    (property "Sheetfile" "csi.kicad_sch")
    (property "Sheetname" "CSI")
    (property "ki_description" "Spacer, SMT, Non Stop, Steel, Swage Round, 5.1 mm x 6 mm, M2.5 Thread, WA-SMSI Series")
    (property "ki_keywords" "MECHANICAL, SPACER")
    (attr smd)
    (fp_text reference "SP2" (at 0 3.2) (layer "B.SilkS") hide
        (effects (font (size 0.7 0.7) (thickness 0.15)) (justify left bottom mirror))
    )
    (fp_text value "Spacer_Drill3.7mm_H6mm_9774060151R" (at 0 -4) (layer "B.Fab")
        (effects (font (size 0.7 0.7) (thickness 0.15)) (justify left bottom mirror))
    )
    (fp_text user "License: Apache-2.0" (at -2.551 -7.75) (layer "B.Fab") hide
        (effects (font (size 0.7 0.7) (thickness 0.15)) (justify left bottom mirror))
    )
    (fp_text user "${REFERENCE}" (at -2.551 -5.25) (layer "B.Fab") hide
        (effects (font (size 0.7 0.7) (thickness 0.15)) (justify left bottom mirror))
    )
    (fp_text user "Author: Antmicro" (at -2.551 -6.5) (layer "B.Fab") hide
        (effects (font (size 0.7 0.7) (thickness 0.15)) (justify left bottom mirror))
    )
    (fp_circle (center 0 0) (end 3.05 0)
      (stroke (width 0.05) (type solid)) (fill none) (layer "B.CrtYd"))
    (fp_circle (center -0.001 0) (end 2.548 0)
      (stroke (width 0.15) (type solid)) (fill none) (layer "B.Fab"))
    (pad "" smd custom (at -1.71 -1.699 90) (size 0.62 0.62) (layers "B.Paste")
      (thermal_bridge_angle 90)
      (options (clearance outline) (anchor circle))
      (primitives
        (gr_arc (start 1.266786 0.24747) (mid 0.285453 -0.29439) (end -0.250195 -1.279127) (width 0.2))
        (gr_arc (start 1.259603 0.339191) (mid 0.218448 -0.232561) (end -0.34334 -1.279127) (width 0.2))
        (gr_arc (start 1.255279 0.431435) (mid 0.152481 -0.169693) (end -0.436309 -1.279127) (width 0.2))
        (gr_arc (start 1.253811 0.524161) (mid 0.087542 -0.105784) (end -0.529126 -1.279127) (width 0.2))
        (gr_arc (start 1.275473 0.621136) (mid 0.0309 -0.033527) (end -0.621807 -1.279127) (width 0.2))
        (gr_arc (start 1.263664 0.711602) (mid -0.037759 0.026651) (end -0.71437 -1.279127) (width 0.2))
        (gr_arc (start 1.253435 0.802342) (mid -0.105837 0.087395) (end -0.806826 -1.279127) (width 0.2))
        (gr_arc (start 1.267475 0.897258) (mid -0.165236 0.156885) (end -0.899187 -1.279127) (width 0.2))
        (gr_arc (start 1.270645 0.990112) (mid -0.228522 0.222449) (end -0.991463 -1.279127) (width 0.2))
        (gr_arc (start 1.266278 1.081674) (mid -0.294507 0.285313) (end -1.083663 -1.279127) (width 0.2))
        (gr_line (start 1.279127 1.083663) (end 1.279127 0.250195) (width 0.2))
        (gr_line (start -1.083663 -1.279127) (end -0.250195 -1.279127) (width 0.2))
      ))
    (pad "" smd custom (at -1.71 1.71 180) (size 0.62 0.62) (layers "B.Paste")
      (thermal_bridge_angle 90)
      (options (clearance outline) (anchor circle))
      (primitives
        (gr_arc (start 1.266786 0.24747) (mid 0.285453 -0.29439) (end -0.250195 -1.279127) (width 0.2))
        (gr_arc (start 1.259603 0.339191) (mid 0.218448 -0.232561) (end -0.34334 -1.279127) (width 0.2))
        (gr_arc (start 1.255279 0.431435) (mid 0.152481 -0.169693) (end -0.436309 -1.279127) (width 0.2))
        (gr_arc (start 1.253811 0.524161) (mid 0.087542 -0.105784) (end -0.529126 -1.279127) (width 0.2))
        (gr_arc (start 1.275473 0.621136) (mid 0.0309 -0.033527) (end -0.621807 -1.279127) (width 0.2))
        (gr_arc (start 1.263664 0.711602) (mid -0.037759 0.026651) (end -0.71437 -1.279127) (width 0.2))
        (gr_arc (start 1.253435 0.802342) (mid -0.105837 0.087395) (end -0.806826 -1.279127) (width 0.2))
        (gr_arc (start 1.267475 0.897258) (mid -0.165236 0.156885) (end -0.899187 -1.279127) (width 0.2))
        (gr_arc (start 1.270645 0.990112) (mid -0.228522 0.222449) (end -0.991463 -1.279127) (width 0.2))
        (gr_arc (start 1.266278 1.081674) (mid -0.294507 0.285313) (end -1.083663 -1.279127) (width 0.2))
        (gr_line (start 1.279127 1.083663) (end 1.279127 0.250195) (width 0.2))
        (gr_line (start -1.083663 -1.279127) (end -0.250195 -1.279127) (width 0.2))
      ))
    (pad "" smd custom (at 1.699 -1.699) (size 0.62 0.62) (layers "B.Paste")
      (thermal_bridge_angle 90)
      (options (clearance outline) (anchor circle))
      (primitives
        (gr_arc (start 1.266786 0.24747) (mid 0.285453 -0.29439) (end -0.250195 -1.279127) (width 0.2))
        (gr_arc (start 1.259603 0.339191) (mid 0.218448 -0.232561) (end -0.34334 -1.279127) (width 0.2))
        (gr_arc (start 1.255279 0.431435) (mid 0.152481 -0.169693) (end -0.436309 -1.279127) (width 0.2))
        (gr_arc (start 1.253811 0.524161) (mid 0.087542 -0.105784) (end -0.529126 -1.279127) (width 0.2))
        (gr_arc (start 1.275473 0.621136) (mid 0.0309 -0.033527) (end -0.621807 -1.279127) (width 0.2))
        (gr_arc (start 1.263664 0.711602) (mid -0.037759 0.026651) (end -0.71437 -1.279127) (width 0.2))
        (gr_arc (start 1.253435 0.802342) (mid -0.105837 0.087395) (end -0.806826 -1.279127) (width 0.2))
        (gr_arc (start 1.267475 0.897258) (mid -0.165236 0.156885) (end -0.899187 -1.279127) (width 0.2))
        (gr_arc (start 1.270645 0.990112) (mid -0.228522 0.222449) (end -0.991463 -1.279127) (width 0.2))
        (gr_arc (start 1.266278 1.081674) (mid -0.294507 0.285313) (end -1.083663 -1.279127) (width 0.2))
        (gr_line (start 1.279127 1.083663) (end 1.279127 0.250195) (width 0.2))
        (gr_line (start -1.083663 -1.279127) (end -0.250195 -1.279127) (width 0.2))
      ))
    (pad "" smd custom (at 1.699 1.71 270) (size 0.62 0.62) (layers "B.Paste")
      (thermal_bridge_angle 90)
      (options (clearance outline) (anchor circle))
      (primitives
        (gr_arc (start 1.266786 0.24747) (mid 0.285453 -0.29439) (end -0.250195 -1.279127) (width 0.2))
        (gr_arc (start 1.259603 0.339191) (mid 0.218448 -0.232561) (end -0.34334 -1.279127) (width 0.2))
        (gr_arc (start 1.255279 0.431435) (mid 0.152481 -0.169693) (end -0.436309 -1.279127) (width 0.2))
        (gr_arc (start 1.253811 0.524161) (mid 0.087542 -0.105784) (end -0.529126 -1.279127) (width 0.2))
        (gr_arc (start 1.275473 0.621136) (mid 0.0309 -0.033527) (end -0.621807 -1.279127) (width 0.2))
        (gr_arc (start 1.263664 0.711602) (mid -0.037759 0.026651) (end -0.71437 -1.279127) (width 0.2))
        (gr_arc (start 1.253435 0.802342) (mid -0.105837 0.087395) (end -0.806826 -1.279127) (width 0.2))
        (gr_arc (start 1.267475 0.897258) (mid -0.165236 0.156885) (end -0.899187 -1.279127) (width 0.2))
        (gr_arc (start 1.270645 0.990112) (mid -0.228522 0.222449) (end -0.991463 -1.279127) (width 0.2))
        (gr_arc (start 1.266278 1.081674) (mid -0.294507 0.285313) (end -1.083663 -1.279127) (width 0.2))
        (gr_line (start 1.279127 1.083663) (end 1.279127 0.250195) (width 0.2))
        (gr_line (start -1.083663 -1.279127) (end -0.250195 -1.279127) (width 0.2))
      ))
    (pad "1" thru_hole circle (at -0.001 0 180) (size 6 6) (drill 3.7) (layers "*.Cu" "*.Mask")
      (net 2 "GND") (pintype "passive") (solder_paste_margin_ratio -0.05))
  )
)
